# S9S_MB_2U (Grand Teton) — schematic netlist excerpt (pin names and nets, part order shuffled) for the footprints in the layout excerpt that follows; sources: Cadence DE-HDL packaged netlist, KiCad conversion of 03242023_DA0F0TMBIJ0_F0T_Motherboard_J_brd_V01_OCP.brd

J111  CONN112_10137002101LF  CONN112_10137002-101LF IO  pkg HSD_F112D8_P2W1-2_RDH  page 142
  A1  = GPU_PEX_STRAP1
  A2  = GND
  A3  = GPU_BASE_ID0
  A4  = GND
  A5  = GPU_PEX_STRAP0
  A6  = GND
  A7  = GPU_FPGA_RST_R_BUF_N
  A8  = GND
  B1  = GND
  B2  = P5E_CPU1_PE0_RX_DN<6>
  B3  = GND
  B4  = P5E_CPU1_PE0_RX_DN<4>
  B5  = GND
  B6  = P5E_CPU1_PE0_RX_DN<2>
  B7  = GND
  B8  = P5E_CPU1_PE0_RX_DN<0>
  C1  = P5E_CPU1_PE0_RX_DN<7>
  C2  = P5E_CPU1_PE0_RX_DP<6>
  C3  = P5E_CPU1_PE0_RX_DN<5>
  C4  = P5E_CPU1_PE0_RX_DP<4>
  C5  = P5E_CPU1_PE0_RX_DP<3>
  C6  = P5E_CPU1_PE0_RX_DP<2>
  C7  = P5E_CPU1_PE0_RX_DP<1>
  C8  = P5E_CPU1_PE0_RX_DP<0>
  D1  = P5E_CPU1_PE0_RX_DP<7>
  D2  = GND
  D3  = P5E_CPU1_PE0_RX_DP<5>
  D4  = GND
  D5  = P5E_CPU1_PE0_RX_DN<3>
  D6  = GND
  D7  = P5E_CPU1_PE0_RX_DN<1>
  D8  = GND
  E1  = GND
  E2  = P5E_CPU1_PE4_RX_DP<9>
  E3  = GND
  E4  = P5E_CPU1_PE4_RX_DP<11>
  E5  = GND
  E6  = P5E_CPU1_PE4_RX_DP<13>
  E7  = GND
  E8  = P5E_CPU1_PE4_RX_DP<15>
  F1  = P5E_CPU1_PE4_RX_DN<8>
  F2  = P5E_CPU1_PE4_RX_DN<9>
  F3  = P5E_CPU1_PE4_RX_DN<10>
  F4  = P5E_CPU1_PE4_RX_DN<11>
  F5  = P5E_CPU1_PE4_RX_DN<12>
  F6  = P5E_CPU1_PE4_RX_DN<13>
  F7  = P5E_CPU1_PE4_RX_DN<14>
  F8  = P5E_CPU1_PE4_RX_DN<15>
  G1  = P5E_CPU1_PE4_RX_DP<8>
  G2  = GND
  G3  = P5E_CPU1_PE4_RX_DP<10>
  G4  = GND
  G5  = P5E_CPU1_PE4_RX_DP<12>
  G6  = GND
  G7  = P5E_CPU1_PE4_RX_DP<14>
  G8  = GND
  H1  = GND
  H2  = P5E_CPU1_PE0_TX_C_DN<6>
  H3  = GND
  H4  = P5E_CPU1_PE0_TX_C_DN<4>
  H5  = GND
  H6  = P5E_CPU1_PE0_TX_C_DN<2>
  H7  = GND
  H8  = P5E_CPU1_PE0_TX_C_DN<0>
  I1  = P5E_CPU1_PE0_TX_C_DN<7>
  I2  = P5E_CPU1_PE0_TX_C_DP<6>
  I3  = P5E_CPU1_PE0_TX_C_DN<5>
  I4  = P5E_CPU1_PE0_TX_C_DP<4>
  I5  = P5E_CPU1_PE0_TX_C_DN<3>
  I6  = P5E_CPU1_PE0_TX_C_DP<2>
  I7  = P5E_CPU1_PE0_TX_C_DN<1>
  I8  = P5E_CPU1_PE0_TX_C_DP<0>
  J1  = P5E_CPU1_PE0_TX_C_DP<7>
  J2  = GND
  J3  = P5E_CPU1_PE0_TX_C_DP<5>
  J4  = GND
  J5  = P5E_CPU1_PE0_TX_C_DP<3>
  J6  = GND
  J7  = P5E_CPU1_PE0_TX_C_DP<1>
  J8  = GND
  K1  = GND
  K2  = P5E_CPU1_PE4_TX_C_DN<9>
  K3  = GND
  K4  = P5E_CPU1_PE4_TX_C_DP<11>
  K5  = GND
  K6  = P5E_CPU1_PE4_TX_C_DN<13>
  K7  = GND
  K8  = P5E_CPU1_PE4_TX_C_DN<15>
  L1  = P5E_CPU1_PE4_TX_C_DN<8>
  L2  = P5E_CPU1_PE4_TX_C_DP<9>
  L3  = P5E_CPU1_PE4_TX_C_DN<10>
  L4  = P5E_CPU1_PE4_TX_C_DN<11>
  L5  = P5E_CPU1_PE4_TX_C_DN<12>
  L6  = P5E_CPU1_PE4_TX_C_DP<13>
  L7  = P5E_CPU1_PE4_TX_C_DN<14>
  L8  = P5E_CPU1_PE4_TX_C_DP<15>
  M1  = P5E_CPU1_PE4_TX_C_DP<8>
  M2  = GND
  M3  = P5E_CPU1_PE4_TX_C_DP<10>
  M4  = GND
  M5  = P5E_CPU1_PE4_TX_C_DP<12>
  M6  = GND
  M7  = P5E_CPU1_PE4_TX_C_DP<14>
  M8  = GND
  N1  = GND
  N2  = GPU_PRSNT_N
  N3  = GND
  N4  = FM_GPU_PWR_EN_R_BUF
  N5  = GND
  N6  = FM_GPU_PWRGD
  N7  = GND
  N8  = GPU_BASE_ID1

(kicad_pcb
	(version 20260206)
	(generator "pcbnew")
	(generator_version "10.0")
	(general
		(thickness 1.6)
		(legacy_teardrops no)
	)
	(paper "A4")
	(title_block
		(title "03242023_DA0F0TMBIJ0_F0T_Motherboard_J_brd_V01_OCP.brd")
		(comment 1 "Grand Teton / footprint 537 of 6105 (J111), pads 32-48 of 48")
	)
	(layers
		(0 "F.Cu" signal "TOP")
		(4 "In1.Cu" signal "GND")
		(6 "In2.Cu" signal "IN1")
		(8 "In3.Cu" signal "GND1")
		(10 "In4.Cu" signal "IN2")
		(12 "In5.Cu" signal "GND2")
		(14 "In6.Cu" signal "IN3")
		(16 "In7.Cu" signal "GND3")
		(18 "In8.Cu" signal "VCC")
		(20 "In9.Cu" signal "VCC1")
		(22 "In10.Cu" signal "GND4")
		(24 "In11.Cu" signal "IN4")
		(26 "In12.Cu" signal "GND5")
		(28 "In13.Cu" signal "IN5")
		(30 "In14.Cu" signal "GND6")
		(32 "In15.Cu" signal "IN6")
		(34 "In16.Cu" signal "GND7")
		(2 "B.Cu" signal "BOTTOM")
		(9 "F.Adhes" user "F.Adhesive")
		(11 "B.Adhes" user "B.Adhesive")
		(13 "F.Paste" user "Package Geometry/Pastemask Top")
		(15 "B.Paste" user "Package Geometry/Pastemask Bottom")
		(5 "F.SilkS" user "Ref Des/Silkscreen Top")
		(7 "B.SilkS" user "Ref Des/Silkscreen Bottom")
		(1 "F.Mask" user "Board Geometry/Soldermask Top")
		(3 "B.Mask" user "Board Geometry/Soldermask Bottom")
		(17 "Dwgs.User" user "User.Drawings")
		(19 "Cmts.User" user "User.Comments")
		(21 "Eco1.User" user "User.Eco1")
		(23 "Eco2.User" user "User.Eco2")
		(25 "Edge.Cuts" user "Board Geometry/Outline")
		(27 "Margin" user)
		(31 "F.CrtYd" user "Package Geometry/Place Bound Top")
		(29 "B.CrtYd" user "Package Geometry/Place Bound Bottom")
		(35 "F.Fab" user "Ref Des/Assembly Top")
		(33 "B.Fab" user "Ref Des/Assembly Bottom")
	)
	(footprint ""
		(layer "F.Cu")
		(at 75.65009 -440.489848)
		(property "Reference" "J111"
			(at 1.96088 23.159212 0)
			(unlocked yes)
			(layer "F.SilkS")
			(effects
				(font
					(size 0.7874 0.5842)
					(thickness 0.1524)
				)
				(justify left)
			)
		)
		(property "Value" ""
			(at 0 0 0)
			(layer "F.Fab")
			(effects
				(font
					(size 1.27 1.27)
				)
			)
		)
		(duplicate_pad_numbers_are_jumpers no)
		(pad "J8" thru_hole circle
			(at 13.999972 10.999978 180)
			(size 0.906272 0.906272)
			(drill 0.499872)
			(layers "*.Cu" "*.Mask")
			(remove_unused_layers no)
			(net "GND")
			(clearance 0.0508)
			(thermal_gap 0.0508)
		)
		(pad "K1" thru_hole circle
			(at 0 11.999976 180)
			(size 0.906272 0.906272)
			(drill 0.499872)
			(layers "*.Cu" "*.Mask")
			(remove_unused_layers no)
			(net "GND")
			(clearance 0.0508)
			(thermal_gap 0.0508)
		)
		(pad "K3" thru_hole circle
			(at 3.999992 11.999976 180)
			(size 0.906272 0.906272)
			(drill 0.499872)
			(layers "*.Cu" "*.Mask")
			(remove_unused_layers no)
			(net "GND")
			(clearance 0.0508)
			(thermal_gap 0.0508)
		)
		(pad "K5" thru_hole circle
			(at 7.999984 11.999976 180)
			(size 0.906272 0.906272)
			(drill 0.499872)
			(layers "*.Cu" "*.Mask")
			(remove_unused_layers no)
			(net "GND")
			(clearance 0.0508)
			(thermal_gap 0.0508)
		)
		(pad "K7" thru_hole circle
			(at 11.999976 11.999976 180)
			(size 0.906272 0.906272)
			(drill 0.499872)
			(layers "*.Cu" "*.Mask")
			(remove_unused_layers no)
			(net "GND")
			(clearance 0.0508)
			(thermal_gap 0.0508)
		)
		(pad "M2" thru_hole circle
			(at 1.999996 14.59992 180)
			(size 0.906272 0.906272)
			(drill 0.499872)
			(layers "*.Cu" "*.Mask")
			(remove_unused_layers no)
			(net "GND")
			(clearance 0.0508)
			(thermal_gap 0.0508)
		)
		(pad "M4" thru_hole circle
			(at 5.999988 14.59992 180)
			(size 0.906272 0.906272)
			(drill 0.499872)
			(layers "*.Cu" "*.Mask")
			(remove_unused_layers no)
			(net "GND")
			(clearance 0.0508)
			(thermal_gap 0.0508)
		)
		(pad "M6" thru_hole circle
			(at 9.99998 14.59992 180)
			(size 0.906272 0.906272)
			(drill 0.499872)
			(layers "*.Cu" "*.Mask")
			(remove_unused_layers no)
			(net "GND")
			(clearance 0.0508)
			(thermal_gap 0.0508)
		)
		(pad "M8" thru_hole circle
			(at 13.999972 14.59992 180)
			(size 0.906272 0.906272)
			(drill 0.499872)
			(layers "*.Cu" "*.Mask")
			(remove_unused_layers no)
			(net "GND")
			(clearance 0.0508)
			(thermal_gap 0.0508)
		)
		(pad "N1" thru_hole circle
			(at 0 15.599918 180)
			(size 0.906272 0.906272)
			(drill 0.499872)
			(layers "*.Cu" "*.Mask")
			(remove_unused_layers no)
			(net "GND")
			(clearance 0.0508)
			(thermal_gap 0.0508)
		)
		(pad "N2" thru_hole circle
			(at 1.999996 15.80007 180)
			(size 0.766318 0.766318)
			(drill 0.359918)
			(layers "*.Cu" "*.Mask")
			(remove_unused_layers no)
			(net "GPU_PRSNT_N")
			(clearance 0.0508)
			(thermal_gap 0.0508)
		)
		(pad "N3" thru_hole circle
			(at 3.999992 15.599918 180)
			(size 0.906272 0.906272)
			(drill 0.499872)
			(layers "*.Cu" "*.Mask")
			(remove_unused_layers no)
			(net "GND")
			(clearance 0.0508)
			(thermal_gap 0.0508)
		)
		(pad "N4" thru_hole circle
			(at 5.999988 15.80007 180)
			(size 0.766318 0.766318)
			(drill 0.359918)
			(layers "*.Cu" "*.Mask")
			(remove_unused_layers no)
			(net "FM_GPU_PWR_EN_R_BUF")
			(clearance 0.0508)
			(thermal_gap 0.0508)
		)
		(pad "N5" thru_hole circle
			(at 7.999984 15.599918 180)
			(size 0.906272 0.906272)
			(drill 0.499872)
			(layers "*.Cu" "*.Mask")
			(remove_unused_layers no)
			(net "GND")
			(clearance 0.0508)
			(thermal_gap 0.0508)
		)
		(pad "N6" thru_hole circle
			(at 9.99998 15.80007 180)
			(size 0.766318 0.766318)
			(drill 0.359918)
			(layers "*.Cu" "*.Mask")
			(remove_unused_layers no)
			(net "FM_GPU_PWRGD")
			(clearance 0.0508)
			(thermal_gap 0.0508)
		)
		(pad "N7" thru_hole circle
			(at 11.999976 15.599918 180)
			(size 0.906272 0.906272)
			(drill 0.499872)
			(layers "*.Cu" "*.Mask")
			(remove_unused_layers no)
			(net "GND")
			(clearance 0.0508)
			(thermal_gap 0.0508)
		)
		(pad "N8" thru_hole circle
			(at 13.999972 15.80007 180)
			(size 0.766318 0.766318)
			(drill 0.359918)
			(layers "*.Cu" "*.Mask")
			(remove_unused_layers no)
			(net "GPU_BASE_ID1")
			(clearance 0.0508)
			(thermal_gap 0.0508)
		)
	)
)
